(kicad_pcb
	(version 20260206)
	(generator "pcbnew")
	(generator_version "10.0")
	(general
		(thickness 1.6)
		(legacy_teardrops no)
	)
	(paper "A4")
	(title_block
		(title "04192023_DAF0TMB3IC0_F0TG_MB_C_brd_V02_OCP.brd")
		(comment 1 "Grand Teton / footprint 4922 of 8354 (J35), pads 1-109 of 175")
	)
	(layers
		(0 "F.Cu" signal "TOP")
		(4 "In1.Cu" signal "GND")
		(6 "In2.Cu" signal "IN1")
		(8 "In3.Cu" signal "GND1")
		(10 "In4.Cu" signal "IN2")
		(12 "In5.Cu" signal "GND2")
		(14 "In6.Cu" signal "IN3")
		(16 "In7.Cu" signal "GND3")
		(18 "In8.Cu" signal "VCC")
		(20 "In9.Cu" signal "VCC1")
		(22 "In10.Cu" signal "GND4")
		(24 "In11.Cu" signal "IN4")
		(26 "In12.Cu" signal "GND5")
		(28 "In13.Cu" signal "IN5")
		(30 "In14.Cu" signal "GND6")
		(32 "In15.Cu" signal "IN6")
		(34 "In16.Cu" signal "GND7")
		(2 "B.Cu" signal "BOTTOM")
		(9 "F.Adhes" user "F.Adhesive")
		(11 "B.Adhes" user "B.Adhesive")
		(13 "F.Paste" user "Package Geometry/Pastemask Top")
		(15 "B.Paste" user "Package Geometry/Pastemask Bottom")
		(5 "F.SilkS" user "Ref Des/Silkscreen Top")
		(7 "B.SilkS" user "Ref Des/Silkscreen Bottom")
		(1 "F.Mask" user "Board Geometry/Soldermask Top")
		(3 "B.Mask" user "Board Geometry/Soldermask Bottom")
		(17 "Dwgs.User" user "User.Drawings")
		(19 "Cmts.User" user "User.Comments")
		(21 "Eco1.User" user "User.Eco1")
		(23 "Eco2.User" user "User.Eco2")
		(25 "Edge.Cuts" user "Board Geometry/Outline")
		(27 "Margin" user)
		(31 "F.CrtYd" user "Package Geometry/Place Bound Top")
		(29 "B.CrtYd" user "Package Geometry/Place Bound Bottom")
		(35 "F.Fab" user "Ref Des/Assembly Top")
		(33 "B.Fab" user "Ref Des/Assembly Bottom")
	)
	(footprint ""
		(layer "F.Cu")
		(at 47.401988 -5.569966 -90)
		(property "Reference" "J35"
			(at -8.0772 -20.659598 0)
			(unlocked yes)
			(layer "F.SilkS")
			(effects
				(font
					(size 0.7874 0.5842)
					(thickness 0.1524)
				)
				(justify left)
			)
		)
		(property "Value" ""
			(at 0 0 270)
			(layer "F.Fab")
			(effects
				(font
					(size 1.27 1.27)
				)
			)
		)
		(duplicate_pad_numbers_are_jumpers no)
		(pad "" np_thru_hole circle
			(at -0.599948 -32.079946 180)
			(size 1.1176 1.1176)
			(drill 1.1176)
			(layers "*.Cu" "*.Mask")
			(clearance 0.381)
			(thermal_gap 0.381)
		)
		(pad "" np_thru_hole circle
			(at 0.40005 32.085026 180)
			(size 1.1176 1.1176)
			(drill 1.1176)
			(layers "*.Cu" "*.Mask")
			(clearance 0.381)
			(thermal_gap 0.381)
		)
		(pad "A1" smd rect
			(at -2.750058 -18.465038 180)
			(size 0.381 1.4478)
			(layers "F.Cu" "F.Mask" "F.Paste")
			(net "GND")
		)
		(pad "A2" smd rect
			(at -2.750058 -17.86509 180)
			(size 0.381 1.4478)
			(layers "F.Cu" "F.Mask" "F.Paste")
			(net "GND")
		)
		(pad "A3" smd rect
			(at -2.750058 -17.264888 180)
			(size 0.381 1.4478)
			(layers "F.Cu" "F.Mask" "F.Paste")
			(net "GND")
		)
		(pad "A4" smd rect
			(at -2.750058 -16.66494 180)
			(size 0.381 1.4478)
			(layers "F.Cu" "F.Mask" "F.Paste")
			(net "GND")
		)
		(pad "A5" smd rect
			(at -2.750058 -16.064992 180)
			(size 0.381 1.4478)
			(layers "F.Cu" "F.Mask" "F.Paste")
			(net "GND")
		)
		(pad "A6" smd rect
			(at -2.750058 -15.465044 180)
			(size 0.381 1.4478)
			(layers "F.Cu" "F.Mask" "F.Paste")
			(net "GND")
		)
		(pad "A7" smd rect
			(at -2.750058 -14.865096 180)
			(size 0.381 1.4478)
			(layers "F.Cu" "F.Mask" "F.Paste")
			(net "SMB_OCP_V3_2_3V3AUX_BUF_R_SCL")
		)
		(pad "A8" smd rect
			(at -2.750058 -14.264894 180)
			(size 0.381 1.4478)
			(layers "F.Cu" "F.Mask" "F.Paste")
			(net "SMB_OCP_V3_2_3V3AUX_BUF_R_SDA")
		)
		(pad "A9" smd rect
			(at -2.750058 -13.664946 180)
			(size 0.381 1.4478)
			(layers "F.Cu" "F.Mask" "F.Paste")
			(net "RST_SMB_OCP_V3_2_N")
		)
		(pad "A10" smd rect
			(at -2.750058 -13.064998 180)
			(size 0.381 1.4478)
			(layers "F.Cu" "F.Mask" "F.Paste")
			(net "OCP_V3_2_PRSNTA_R_N")
		)
		(pad "A11" smd rect
			(at -2.750058 -12.46505 180)
			(size 0.381 1.4478)
			(layers "F.Cu" "F.Mask" "F.Paste")
			(net "RST_PERST1_OCP_V3_2_N")
		)
		(pad "A12" smd rect
			(at -2.750058 -11.865102 180)
			(size 0.381 1.4478)
			(layers "F.Cu" "F.Mask" "F.Paste")
			(net "OCP_V3_2_PRSNT2_R_N")
		)
		(pad "A13" smd rect
			(at -2.750058 -11.2649 180)
			(size 0.381 1.4478)
			(layers "F.Cu" "F.Mask" "F.Paste")
			(net "GND")
		)
		(pad "A14" smd rect
			(at -2.750058 -10.664952 180)
			(size 0.381 1.4478)
			(layers "F.Cu" "F.Mask" "F.Paste")
			(net "CLK_100M_CPU1_CLK03_DN")
		)
		(pad "A15" smd rect
			(at -2.750058 -10.065004 180)
			(size 0.381 1.4478)
			(layers "F.Cu" "F.Mask" "F.Paste")
			(net "CLK_100M_CPU1_CLK03_DP")
		)
		(pad "A16" smd rect
			(at -2.750058 -9.465056 180)
			(size 0.381 1.4478)
			(layers "F.Cu" "F.Mask" "F.Paste")
			(net "GND")
		)
		(pad "A17" smd rect
			(at -2.750058 -8.865108 180)
			(size 0.381 1.4478)
			(layers "F.Cu" "F.Mask" "F.Paste")
			(net "P5E_CPU1_G1_RX_DN<0>")
		)
		(pad "A18" smd rect
			(at -2.750058 -8.264906 180)
			(size 0.381 1.4478)
			(layers "F.Cu" "F.Mask" "F.Paste")
			(net "P5E_CPU1_G1_RX_DP<0>")
		)
		(pad "A19" smd rect
			(at -2.750058 -7.664958 180)
			(size 0.381 1.4478)
			(layers "F.Cu" "F.Mask" "F.Paste")
			(net "GND")
		)
		(pad "A20" smd rect
			(at -2.750058 -7.06501 180)
			(size 0.381 1.4478)
			(layers "F.Cu" "F.Mask" "F.Paste")
			(net "P5E_CPU1_G1_RX_DN<1>")
		)
		(pad "A21" smd rect
			(at -2.750058 -6.465062 180)
			(size 0.381 1.4478)
			(layers "F.Cu" "F.Mask" "F.Paste")
			(net "P5E_CPU1_G1_RX_DP<1>")
		)
		(pad "A22" smd rect
			(at -2.750058 -5.865114 180)
			(size 0.381 1.4478)
			(layers "F.Cu" "F.Mask" "F.Paste")
			(net "GND")
		)
		(pad "A23" smd rect
			(at -2.750058 -5.264912 180)
			(size 0.381 1.4478)
			(layers "F.Cu" "F.Mask" "F.Paste")
			(net "P5E_CPU1_G1_RX_DN<2>")
		)
		(pad "A24" smd rect
			(at -2.750058 -4.664964 180)
			(size 0.381 1.4478)
			(layers "F.Cu" "F.Mask" "F.Paste")
			(net "P5E_CPU1_G1_RX_DP<2>")
		)
		(pad "A25" smd rect
			(at -2.750058 -4.065016 180)
			(size 0.381 1.4478)
			(layers "F.Cu" "F.Mask" "F.Paste")
			(net "GND")
		)
		(pad "A26" smd rect
			(at -2.750058 -3.465068 180)
			(size 0.381 1.4478)
			(layers "F.Cu" "F.Mask" "F.Paste")
			(net "P5E_CPU1_G1_RX_DN<3>")
		)
		(pad "A27" smd rect
			(at -2.750058 -2.86512 180)
			(size 0.381 1.4478)
			(layers "F.Cu" "F.Mask" "F.Paste")
			(net "P5E_CPU1_G1_RX_DP<3>")
		)
		(pad "A28" smd rect
			(at -2.750058 -2.264918 180)
			(size 0.381 1.4478)
			(layers "F.Cu" "F.Mask" "F.Paste")
			(net "GND")
		)
		(pad "A29" smd rect
			(at -2.750058 1.74498 180)
			(size 0.381 1.4478)
			(layers "F.Cu" "F.Mask" "F.Paste")
			(net "GND")
		)
		(pad "A30" smd rect
			(at -2.750058 2.344928 180)
			(size 0.381 1.4478)
			(layers "F.Cu" "F.Mask" "F.Paste")
			(net "P5E_CPU1_G1_RX_DN<4>")
		)
		(pad "A31" smd rect
			(at -2.750058 2.944876 180)
			(size 0.381 1.4478)
			(layers "F.Cu" "F.Mask" "F.Paste")
			(net "P5E_CPU1_G1_RX_DP<4>")
		)
		(pad "A32" smd rect
			(at -2.750058 3.545078 180)
			(size 0.381 1.4478)
			(layers "F.Cu" "F.Mask" "F.Paste")
			(net "GND")
		)
		(pad "A33" smd rect
			(at -2.750058 4.145026 180)
			(size 0.381 1.4478)
			(layers "F.Cu" "F.Mask" "F.Paste")
			(net "P5E_CPU1_G1_RX_DN<5>")
		)
		(pad "A34" smd rect
			(at -2.750058 4.744974 180)
			(size 0.381 1.4478)
			(layers "F.Cu" "F.Mask" "F.Paste")
			(net "P5E_CPU1_G1_RX_DP<5>")
		)
		(pad "A35" smd rect
			(at -2.750058 5.344922 180)
			(size 0.381 1.4478)
			(layers "F.Cu" "F.Mask" "F.Paste")
			(net "GND")
		)
		(pad "A36" smd rect
			(at -2.750058 5.945124 180)
			(size 0.381 1.4478)
			(layers "F.Cu" "F.Mask" "F.Paste")
			(net "P5E_CPU1_G1_RX_DN<6>")
		)
		(pad "A37" smd rect
			(at -2.750058 6.545072 180)
			(size 0.381 1.4478)
			(layers "F.Cu" "F.Mask" "F.Paste")
			(net "P5E_CPU1_G1_RX_DP<6>")
		)
		(pad "A38" smd rect
			(at -2.750058 7.14502 180)
			(size 0.381 1.4478)
			(layers "F.Cu" "F.Mask" "F.Paste")
			(net "GND")
		)
		(pad "A39" smd rect
			(at -2.750058 7.744968 180)
			(size 0.381 1.4478)
			(layers "F.Cu" "F.Mask" "F.Paste")
			(net "P5E_CPU1_G1_RX_DN<7>")
		)
		(pad "A40" smd rect
			(at -2.750058 8.344916 180)
			(size 0.381 1.4478)
			(layers "F.Cu" "F.Mask" "F.Paste")
			(net "P5E_CPU1_G1_RX_DP<7>")
		)
		(pad "A41" smd rect
			(at -2.750058 8.945118 180)
			(size 0.381 1.4478)
			(layers "F.Cu" "F.Mask" "F.Paste")
			(net "GND")
		)
		(pad "A42" smd rect
			(at -2.750058 9.545066 180)
			(size 0.381 1.4478)
			(layers "F.Cu" "F.Mask" "F.Paste")
			(net "OCP_V3_2_PRSNT1_R_N")
		)
		(pad "A43" smd rect
			(at -2.750058 14.454886 180)
			(size 0.381 1.4478)
			(layers "F.Cu" "F.Mask" "F.Paste")
			(net "GND")
		)
		(pad "A44" smd rect
			(at -2.750058 15.055088 180)
			(size 0.381 1.4478)
			(layers "F.Cu" "F.Mask" "F.Paste")
			(net "P5E_CPU1_G1_RX_DN<8>")
		)
		(pad "A45" smd rect
			(at -2.750058 15.655036 180)
			(size 0.381 1.4478)
			(layers "F.Cu" "F.Mask" "F.Paste")
			(net "P5E_CPU1_G1_RX_DP<8>")
		)
		(pad "A46" smd rect
			(at -2.750058 16.254984 180)
			(size 0.381 1.4478)
			(layers "F.Cu" "F.Mask" "F.Paste")
			(net "GND")
		)
		(pad "A47" smd rect
			(at -2.750058 16.854932 180)
			(size 0.381 1.4478)
			(layers "F.Cu" "F.Mask" "F.Paste")
			(net "P5E_CPU1_G1_RX_DN<9>")
		)
		(pad "A48" smd rect
			(at -2.750058 17.45488 180)
			(size 0.381 1.4478)
			(layers "F.Cu" "F.Mask" "F.Paste")
			(net "P5E_CPU1_G1_RX_DP<9>")
		)
		(pad "A49" smd rect
			(at -2.750058 18.055082 180)
			(size 0.381 1.4478)
			(layers "F.Cu" "F.Mask" "F.Paste")
			(net "GND")
		)
		(pad "A50" smd rect
			(at -2.750058 18.65503 180)
			(size 0.381 1.4478)
			(layers "F.Cu" "F.Mask" "F.Paste")
			(net "P5E_CPU1_G1_RX_DN<10>")
		)
		(pad "A51" smd rect
			(at -2.750058 19.254978 180)
			(size 0.381 1.4478)
			(layers "F.Cu" "F.Mask" "F.Paste")
			(net "P5E_CPU1_G1_RX_DP<10>")
		)
		(pad "A52" smd rect
			(at -2.750058 19.854926 180)
			(size 0.381 1.4478)
			(layers "F.Cu" "F.Mask" "F.Paste")
			(net "GND")
		)
		(pad "A53" smd rect
			(at -2.750058 20.455128 180)
			(size 0.381 1.4478)
			(layers "F.Cu" "F.Mask" "F.Paste")
			(net "P5E_CPU1_G1_RX_DN<11>")
		)
		(pad "A54" smd rect
			(at -2.750058 21.055076 180)
			(size 0.381 1.4478)
			(layers "F.Cu" "F.Mask" "F.Paste")
			(net "P5E_CPU1_G1_RX_DP<11>")
		)
		(pad "A55" smd rect
			(at -2.750058 21.655024 180)
			(size 0.381 1.4478)
			(layers "F.Cu" "F.Mask" "F.Paste")
			(net "GND")
		)
		(pad "A56" smd rect
			(at -2.750058 22.254972 180)
			(size 0.381 1.4478)
			(layers "F.Cu" "F.Mask" "F.Paste")
			(net "P5E_CPU1_G1_RX_DN<12>")
		)
		(pad "A57" smd rect
			(at -2.750058 22.85492 180)
			(size 0.381 1.4478)
			(layers "F.Cu" "F.Mask" "F.Paste")
			(net "P5E_CPU1_G1_RX_DP<12>")
		)
		(pad "A58" smd rect
			(at -2.750058 23.455122 180)
			(size 0.381 1.4478)
			(layers "F.Cu" "F.Mask" "F.Paste")
			(net "GND")
		)
		(pad "A59" smd rect
			(at -2.750058 24.05507 180)
			(size 0.381 1.4478)
			(layers "F.Cu" "F.Mask" "F.Paste")
			(net "P5E_CPU1_G1_RX_DN<13>")
		)
		(pad "A60" smd rect
			(at -2.750058 24.655018 180)
			(size 0.381 1.4478)
			(layers "F.Cu" "F.Mask" "F.Paste")
			(net "P5E_CPU1_G1_RX_DP<13>")
		)
		(pad "A61" smd rect
			(at -2.750058 25.254966 180)
			(size 0.381 1.4478)
			(layers "F.Cu" "F.Mask" "F.Paste")
			(net "GND")
		)
		(pad "A62" smd rect
			(at -2.750058 25.854914 180)
			(size 0.381 1.4478)
			(layers "F.Cu" "F.Mask" "F.Paste")
			(net "P5E_CPU1_G1_RX_DN<14>")
		)
		(pad "A63" smd rect
			(at -2.750058 26.455116 180)
			(size 0.381 1.4478)
			(layers "F.Cu" "F.Mask" "F.Paste")
			(net "P5E_CPU1_G1_RX_DP<14>")
		)
		(pad "A64" smd rect
			(at -2.750058 27.055064 180)
			(size 0.381 1.4478)
			(layers "F.Cu" "F.Mask" "F.Paste")
			(net "GND")
		)
		(pad "A65" smd rect
			(at -2.750058 27.655012 180)
			(size 0.381 1.4478)
			(layers "F.Cu" "F.Mask" "F.Paste")
			(net "P5E_CPU1_G1_RX_DN<15>")
		)
		(pad "A66" smd rect
			(at -2.750058 28.25496 180)
			(size 0.381 1.4478)
			(layers "F.Cu" "F.Mask" "F.Paste")
			(net "P5E_CPU1_G1_RX_DP<15>")
		)
		(pad "A67" smd rect
			(at -2.750058 28.854908 180)
			(size 0.381 1.4478)
			(layers "F.Cu" "F.Mask" "F.Paste")
			(net "GND")
		)
		(pad "A68" smd rect
			(at -2.750058 29.45511 180)
			(size 0.381 1.4478)
			(layers "F.Cu" "F.Mask" "F.Paste")
			(net "USB2_P10_DN")
		)
		(pad "A69" smd rect
			(at -2.750058 30.055058 180)
			(size 0.381 1.4478)
			(layers "F.Cu" "F.Mask" "F.Paste")
			(net "USB2_P10_DP")
		)
		(pad "A70" smd rect
			(at -2.750058 30.655006 180)
			(size 0.381 1.4478)
			(layers "F.Cu" "F.Mask" "F.Paste")
			(net "OCP_V3_2_PWRBRK_N")
		)
		(pad "B1" smd rect
			(at -5.700014 -18.465038 180)
			(size 0.381 1.4478)
			(layers "F.Cu" "F.Mask" "F.Paste")
			(net "P12V_OCP_V3_2_R")
		)
		(pad "B2" smd rect
			(at -5.700014 -17.86509 180)
			(size 0.381 1.4478)
			(layers "F.Cu" "F.Mask" "F.Paste")
			(net "P12V_OCP_V3_2_R")
		)
		(pad "B3" smd rect
			(at -5.700014 -17.264888 180)
			(size 0.381 1.4478)
			(layers "F.Cu" "F.Mask" "F.Paste")
			(net "P12V_OCP_V3_2_R")
		)
		(pad "B4" smd rect
			(at -5.700014 -16.66494 180)
			(size 0.381 1.4478)
			(layers "F.Cu" "F.Mask" "F.Paste")
			(net "P12V_OCP_V3_2_R")
		)
		(pad "B5" smd rect
			(at -5.700014 -16.064992 180)
			(size 0.381 1.4478)
			(layers "F.Cu" "F.Mask" "F.Paste")
			(net "P12V_OCP_V3_2_R")
		)
		(pad "B6" smd rect
			(at -5.700014 -15.465044 180)
			(size 0.381 1.4478)
			(layers "F.Cu" "F.Mask" "F.Paste")
			(net "P12V_OCP_V3_2_R")
		)
		(pad "B7" smd rect
			(at -5.700014 -14.865096 180)
			(size 0.381 1.4478)
			(layers "F.Cu" "F.Mask" "F.Paste")
			(net "OCP_V3_2_BIF0_R_N")
		)
		(pad "B8" smd rect
			(at -5.700014 -14.264894 180)
			(size 0.381 1.4478)
			(layers "F.Cu" "F.Mask" "F.Paste")
			(net "OCP_V3_2_BIF1_R_N")
		)
		(pad "B9" smd rect
			(at -5.700014 -13.664946 180)
			(size 0.381 1.4478)
			(layers "F.Cu" "F.Mask" "F.Paste")
			(net "OCP_V3_2_BIF2_R_N")
		)
		(pad "B10" smd rect
			(at -5.700014 -13.064998 180)
			(size 0.381 1.4478)
			(layers "F.Cu" "F.Mask" "F.Paste")
			(net "RST_PERST0_OCP_V3_2_N")
		)
		(pad "B11" smd rect
			(at -5.700014 -12.46505 180)
			(size 0.381 1.4478)
			(layers "F.Cu" "F.Mask" "F.Paste")
			(net "P3V3_OCP_V3_2")
		)
		(pad "B12" smd rect
			(at -5.700014 -11.865102 180)
			(size 0.381 1.4478)
			(layers "F.Cu" "F.Mask" "F.Paste")
			(net "OCP_V3_2_AUX_PWR_EN_R")
		)
		(pad "B13" smd rect
			(at -5.700014 -11.2649 180)
			(size 0.381 1.4478)
			(layers "F.Cu" "F.Mask" "F.Paste")
			(net "GND")
		)
		(pad "B14" smd rect
			(at -5.700014 -10.664952 180)
			(size 0.381 1.4478)
			(layers "F.Cu" "F.Mask" "F.Paste")
			(net "CLK_100M_CPU1_CLK02_DN")
		)
		(pad "B15" smd rect
			(at -5.700014 -10.065004 180)
			(size 0.381 1.4478)
			(layers "F.Cu" "F.Mask" "F.Paste")
			(net "CLK_100M_CPU1_CLK02_DP")
		)
		(pad "B16" smd rect
			(at -5.700014 -9.465056 180)
			(size 0.381 1.4478)
			(layers "F.Cu" "F.Mask" "F.Paste")
			(net "GND")
		)
		(pad "B17" smd rect
			(at -5.700014 -8.865108 180)
			(size 0.381 1.4478)
			(layers "F.Cu" "F.Mask" "F.Paste")
			(net "P5E_CPU1_G1_TX_C_DP<0>")
		)
		(pad "B18" smd rect
			(at -5.700014 -8.264906 180)
			(size 0.381 1.4478)
			(layers "F.Cu" "F.Mask" "F.Paste")
			(net "P5E_CPU1_G1_TX_C_DN<0>")
		)
		(pad "B19" smd rect
			(at -5.700014 -7.664958 180)
			(size 0.381 1.4478)
			(layers "F.Cu" "F.Mask" "F.Paste")
			(net "GND")
		)
		(pad "B20" smd rect
			(at -5.700014 -7.06501 180)
			(size 0.381 1.4478)
			(layers "F.Cu" "F.Mask" "F.Paste")
			(net "P5E_CPU1_G1_TX_C_DP<1>")
		)
		(pad "B21" smd rect
			(at -5.700014 -6.465062 180)
			(size 0.381 1.4478)
			(layers "F.Cu" "F.Mask" "F.Paste")
			(net "P5E_CPU1_G1_TX_C_DN<1>")
		)
		(pad "B22" smd rect
			(at -5.700014 -5.865114 180)
			(size 0.381 1.4478)
			(layers "F.Cu" "F.Mask" "F.Paste")
			(net "GND")
		)
		(pad "B23" smd rect
			(at -5.700014 -5.264912 180)
			(size 0.381 1.4478)
			(layers "F.Cu" "F.Mask" "F.Paste")
			(net "P5E_CPU1_G1_TX_C_DP<2>")
		)
		(pad "B24" smd rect
			(at -5.700014 -4.664964 180)
			(size 0.381 1.4478)
			(layers "F.Cu" "F.Mask" "F.Paste")
			(net "P5E_CPU1_G1_TX_C_DN<2>")
		)
		(pad "B25" smd rect
			(at -5.700014 -4.065016 180)
			(size 0.381 1.4478)
			(layers "F.Cu" "F.Mask" "F.Paste")
			(net "GND")
		)
		(pad "B26" smd rect
			(at -5.700014 -3.465068 180)
			(size 0.381 1.4478)
			(layers "F.Cu" "F.Mask" "F.Paste")
			(net "P5E_CPU1_G1_TX_C_DP<3>")
		)
		(pad "B27" smd rect
			(at -5.700014 -2.86512 180)
			(size 0.381 1.4478)
			(layers "F.Cu" "F.Mask" "F.Paste")
			(net "P5E_CPU1_G1_TX_C_DN<3>")
		)
		(pad "B28" smd rect
			(at -5.700014 -2.264918 180)
			(size 0.381 1.4478)
			(layers "F.Cu" "F.Mask" "F.Paste")
			(net "GND")
		)
		(pad "B29" smd rect
			(at -5.700014 1.74498 180)
			(size 0.381 1.4478)
			(layers "F.Cu" "F.Mask" "F.Paste")
			(net "GND")
		)
		(pad "B30" smd rect
			(at -5.700014 2.344928 180)
			(size 0.381 1.4478)
			(layers "F.Cu" "F.Mask" "F.Paste")
			(net "P5E_CPU1_G1_TX_C_DP<4>")
		)
		(pad "B31" smd rect
			(at -5.700014 2.944876 180)
			(size 0.381 1.4478)
			(layers "F.Cu" "F.Mask" "F.Paste")
			(net "P5E_CPU1_G1_TX_C_DN<4>")
		)
		(pad "B32" smd rect
			(at -5.700014 3.545078 180)
			(size 0.381 1.4478)
			(layers "F.Cu" "F.Mask" "F.Paste")
			(net "GND")
		)
		(pad "B33" smd rect
			(at -5.700014 4.145026 180)
			(size 0.381 1.4478)
			(layers "F.Cu" "F.Mask" "F.Paste")
			(net "P5E_CPU1_G1_TX_C_DP<5>")
		)
		(pad "B34" smd rect
			(at -5.700014 4.744974 180)
			(size 0.381 1.4478)
			(layers "F.Cu" "F.Mask" "F.Paste")
			(net "P5E_CPU1_G1_TX_C_DN<5>")
		)
		(pad "B35" smd rect
			(at -5.700014 5.344922 180)
			(size 0.381 1.4478)
			(layers "F.Cu" "F.Mask" "F.Paste")
			(net "GND")
		)
		(pad "B36" smd rect
			(at -5.700014 5.945124 180)
			(size 0.381 1.4478)
			(layers "F.Cu" "F.Mask" "F.Paste")
			(net "P5E_CPU1_G1_TX_C_DP<6>")
		)
		(pad "B37" smd rect
			(at -5.700014 6.545072 180)
			(size 0.381 1.4478)
			(layers "F.Cu" "F.Mask" "F.Paste")
			(net "P5E_CPU1_G1_TX_C_DN<6>")
		)
	)
)
